(kicad_pcb
	(version 20260206)
	(generator "pcbnew")
	(generator_version "10.0")
	(general
		(thickness 1.6)
		(legacy_teardrops no)
	)
	(paper "A4")
	(title_block
		(title "Bryce Canyon_R.DPB_16317-1_OCP.brd")
		(comment 1 "Bryce Canyon / footprints 834-838 of 2099")
	)
	(layers
		(0 "F.Cu" signal "TOP")
		(4 "In1.Cu" signal "L2GND")
		(6 "In2.Cu" signal "L3")
		(8 "In3.Cu" signal "L4VCC")
		(10 "In4.Cu" signal "L5VCC")
		(12 "In5.Cu" signal "L6")
		(14 "In6.Cu" signal "L7GND")
		(2 "B.Cu" signal "BOTTOM")
		(9 "F.Adhes" user "F.Adhesive")
		(11 "B.Adhes" user "B.Adhesive")
		(13 "F.Paste" user "Package Geometry/Pastemask Top")
		(15 "B.Paste" user "Package Geometry/Pastemask Bottom")
		(5 "F.SilkS" user "Ref Des/Silkscreen Top")
		(7 "B.SilkS" user "Ref Des/Silkscreen Bottom")
		(1 "F.Mask" user "Board Geometry/Soldermask Top")
		(3 "B.Mask" user "Board Geometry/Soldermask Bottom")
		(17 "Dwgs.User" user "User.Drawings")
		(19 "Cmts.User" user "User.Comments")
		(21 "Eco1.User" user "User.Eco1")
		(23 "Eco2.User" user "User.Eco2")
		(25 "Edge.Cuts" user "Board Geometry/Outline")
		(27 "Margin" user)
		(31 "F.CrtYd" user "Package Geometry/Place Bound Top")
		(29 "B.CrtYd" user "Package Geometry/Place Bound Bottom")
		(35 "F.Fab" user "Ref Des/Assembly Top")
		(33 "B.Fab" user "Ref Des/Assembly Bottom")
	)
	(footprint ""
		(layer "F.Cu")
		(at 159.324802 -63.799974)
		(property "Reference" ""
			(at 0 0 0)
			(layer "F.SilkS")
			(hide yes)
			(effects
				(font
					(size 1.27 1.27)
				)
			)
		)
		(property "Value" "*"
			(at -8.398764 -8.057642 0)
			(unlocked yes)
			(layer "F.Fab")
			(hide yes)
			(effects
				(font
					(size 1.016 1.016)
					(thickness 0.1524)
				)
			)
		)
		(duplicate_pad_numbers_are_jumpers no)
		(fp_poly
			(pts
				(arc
					(start 7.3152 0)
					(mid 0 7.3152)
					(end -7.3152 0)
				)
				(arc
					(start -7.3152 -5.9944)
					(mid 0 -13.3096)
					(end 7.3152 -5.9944)
				)
			)
			(stroke
				(width 0)
				(type default)
			)
			(fill no)
			(layer "B.CrtYd")
		)
		(fp_poly
			(pts
				(arc
					(start 7.3152 0)
					(mid 0 7.3152)
					(end -7.3152 0)
				)
				(arc
					(start -7.3152 -5.9944)
					(mid 0 -13.3096)
					(end 7.3152 -5.9944)
				)
			)
			(stroke
				(width 0)
				(type default)
			)
			(fill no)
			(layer "F.CrtYd")
		)
		(fp_poly
			(pts
				(arc
					(start 7.3152 0)
					(mid 0 7.3152)
					(end -7.3152 0)
				)
				(arc
					(start -7.3152 -5.9944)
					(mid 0 -13.3096)
					(end 7.3152 -5.9944)
				)
			)
			(stroke
				(width 0)
				(type default)
			)
			(fill no)
			(layer "B.Fab")
		)
		(fp_poly
			(pts
				(arc
					(start 7.3152 0)
					(mid 0 7.3152)
					(end -7.3152 0)
				)
				(arc
					(start -7.3152 -5.9944)
					(mid 0 -13.3096)
					(end 7.3152 -5.9944)
				)
			)
			(stroke
				(width 0)
				(type default)
			)
			(fill no)
			(layer "F.Fab")
		)
		(pad "1" thru_hole oval
			(at 0 0)
			(size 14.0208 20.0152)
			(drill 0.0254
				(offset 0 -2.9972)
			)
			(layers "*.Cu" "*.Mask")
			(remove_unused_layers no)
			(net "Net_49")
			(clearance -1.002284)
			(thermal_gap 0.1524)
			(padstack
				(mode front_inner_back)
				(layer "Inner"
					(shape custom)
					(size 2.928012 2.928012)
					(options
						(anchor circle)
					)
					(primitives
						(gr_poly
							(pts
								(arc
									(start 4.571746 -2.084324)
									(mid 0.000333 7.430372)
									(end -4.571492 -2.084324)
								)
								(arc
									(start -4.571492 -2.084324)
									(mid -3.570296 -3.611977)
									(end -2.875026 -5.30098)
								)
								(arc
									(start -2.875026 -5.30098)
									(mid 0.000217 -7.43089)
									(end 2.87528 -5.30098)
								)
								(arc
									(start 2.87528 -5.30098)
									(mid 3.570511 -3.611956)
									(end 4.571746 -2.084324)
								)
							)
							(width 0)
							(fill yes)
						)
					)
					(clearance 0.1524)
				)
				(layer "B.Cu"
					(shape oval)
					(size 14.0208 20.0152)
					(offset 0 -2.9972)
					(clearance -1.002284)
				)
			)
		)
		(zone
			(layers "F.Cu" "B.Cu" "In1.Cu" "In2.Cu" "In3.Cu" "In4.Cu" "In5.Cu" "In6.Cu")
			(hatch none 0.5)
			(connect_pads
				(clearance 0)
			)
			(min_thickness 0.25)
			(keepout
				(tracks not_allowed)
				(vias allowed)
				(pads allowed)
				(copperpour not_allowed)
				(footprints allowed)
			)
			(placement
				(enabled no)
				(sheetname "")
			)
			(fill
				(thermal_gap 0.5)
				(thermal_bridge_width 0.5)
				(island_removal_mode 0)
			)
			(polygon
				(pts
					(arc
						(start 152.314402 -69.794374)
						(mid 159.324802 -76.804774)
						(end 166.335202 -69.794374)
					)
					(arc
						(start 166.335202 -63.799974)
						(mid 159.324802 -56.789574)
						(end 152.314402 -63.799974)
					)
				)
			)
		)
	)
	(footprint ""
		(layer "F.Cu")
		(at 267.854938 -96.28886 -90)
		(property "Reference" "TC15"
			(at 0 0 270)
			(layer "F.SilkS")
			(hide yes)
			(effects
				(font
					(size 1.27 1.27)
				)
			)
		)
		(property "Value" "ST100U16VDM-3-GP"
			(at 0 -9.6012 270)
			(unlocked yes)
			(layer "F.Fab")
			(hide yes)
			(effects
				(font
					(size 1.016 1.016)
					(thickness 0.1524)
				)
			)
		)
		(property "Device Type" "CT7343H79"
			(at 0 -11.1252 270)
			(unlocked yes)
			(layer "F.Fab")
			(hide yes)
			(effects
				(font
					(size 1.016 1.016)
					(thickness 0.1524)
				)
			)
		)
		(duplicate_pad_numbers_are_jumpers no)
		(fp_line
			(start -2.286 4.8768)
			(end -2.286 2.032)
			(stroke
				(width 0.1524)
				(type default)
			)
			(layer "F.SilkS")
		)
		(fp_line
			(start 2.286 4.8768)
			(end -2.286 4.8768)
			(stroke
				(width 0.1524)
				(type default)
			)
			(layer "F.SilkS")
		)
		(fp_line
			(start 2.286 2.032)
			(end 2.286 4.8768)
			(stroke
				(width 0.1524)
				(type default)
			)
			(layer "F.SilkS")
		)
		(fp_line
			(start 2.286 -2.032)
			(end 2.286 -4.8768)
			(stroke
				(width 0.1524)
				(type default)
			)
			(layer "F.SilkS")
		)
		(fp_line
			(start 2.1082 -4.699)
			(end -2.1082 -4.699)
			(stroke
				(width 0.508)
				(type default)
			)
			(layer "F.SilkS")
		)
		(fp_line
			(start -2.286 -4.8768)
			(end -2.286 -2.032)
			(stroke
				(width 0.1524)
				(type default)
			)
			(layer "F.SilkS")
		)
		(fp_line
			(start 2.286 -4.8768)
			(end -2.286 -4.8768)
			(stroke
				(width 0.1524)
				(type default)
			)
			(layer "F.SilkS")
		)
		(fp_rect
			(start -2.1463 3.6449)
			(end 2.1463 -3.6449)
			(stroke
				(width 0)
				(type default)
			)
			(fill no)
			(layer "F.CrtYd")
		)
		(fp_poly
			(pts
				(xy -2.54 4.953) (xy -2.54 4.2926) (xy -3.81 4.2926) (xy -3.81 -4.2926) (xy -2.54 -4.2926) (xy -2.54 -4.953)
				(xy 2.54 -4.953) (xy 2.54 -4.2926) (xy 3.81 -4.2926) (xy 3.81 -1.6256) (xy 2.1463 -1.6256) (xy 2.1463 -3.6449)
				(xy -2.1463 -3.6449) (xy -2.1463 3.6449) (xy 2.1463 3.6449) (xy 2.1463 -1.6129) (xy 3.81 -1.6129)
				(xy 3.81 4.2926) (xy 2.54 4.2926) (xy 2.54 4.953)
			)
			(stroke
				(width 0)
				(type default)
			)
			(fill no)
			(layer "F.CrtYd")
		)
		(fp_rect
			(start -2.54 4.953)
			(end 2.54 -4.953)
			(stroke
				(width 0)
				(type default)
			)
			(fill no)
			(layer "F.Fab")
		)
		(fp_rect
			(start -3.81 4.2926)
			(end -2.54 -4.2926)
			(stroke
				(width 0)
				(type default)
			)
			(fill no)
			(layer "F.Fab")
		)
		(fp_rect
			(start 2.54 4.2926)
			(end 3.81 -4.2926)
			(stroke
				(width 0)
				(type default)
			)
			(fill no)
			(layer "F.Fab")
		)
		(pad "1" smd rect
			(at 0 -3.1496 270)
			(size 2.413 2.286)
			(layers "F.Cu" "F.Mask" "F.Paste")
			(net "P12V_IN")
		)
		(pad "2" smd rect
			(at 0 3.1496 270)
			(size 2.413 2.286)
			(layers "F.Cu" "F.Mask" "F.Paste")
			(net "GND")
		)
		(zone
			(layer "F.Cu")
			(hatch none 0.5)
			(connect_pads
				(clearance 0)
			)
			(min_thickness 0.25)
			(keepout
				(tracks allowed)
				(vias not_allowed)
				(pads allowed)
				(copperpour not_allowed)
				(footprints allowed)
			)
			(placement
				(enabled no)
				(sheetname "")
			)
			(fill
				(thermal_gap 0.5)
				(thermal_bridge_width 0.5)
				(island_removal_mode 0)
			)
			(polygon
				(pts
					(xy 263.257538 -97.80016) (xy 263.257538 -94.77756) (xy 266.153138 -94.77756) (xy 266.483338 -94.77756)
					(xy 266.483338 -97.80016) (xy 266.153138 -97.80016)
				)
			)
		)
		(zone
			(layer "F.Cu")
			(hatch none 0.5)
			(connect_pads
				(clearance 0)
			)
			(min_thickness 0.25)
			(keepout
				(tracks allowed)
				(vias not_allowed)
				(pads allowed)
				(copperpour not_allowed)
				(footprints allowed)
			)
			(placement
				(enabled no)
				(sheetname "")
			)
			(fill
				(thermal_gap 0.5)
				(thermal_bridge_width 0.5)
				(island_removal_mode 0)
			)
			(polygon
				(pts
					(xy 269.544038 -94.77756) (xy 272.452338 -94.77756) (xy 272.452338 -97.80016) (xy 269.556738 -97.80016)
					(xy 269.226538 -97.80016) (xy 269.226538 -94.77756)
				)
			)
		)
	)
	(footprint ""
		(layer "F.Cu")
		(at 469.654128 -214.757 180)
		(property "Reference" "Q230"
			(at 0 0 180)
			(layer "F.SilkS")
			(hide yes)
			(effects
				(font
					(size 1.27 1.27)
				)
			)
		)
		(property "Value" "2N7002K-2-GP"
			(at 0.127 -8.9662 180)
			(unlocked yes)
			(layer "F.Fab")
			(hide yes)
			(effects
				(font
					(size 1.016 1.016)
					(thickness 0.1524)
				)
			)
		)
		(property "Device Type" "SOT23DGS2D4H44"
			(at 0.127 -10.4902 180)
			(unlocked yes)
			(layer "F.Fab")
			(hide yes)
			(effects
				(font
					(size 1.016 1.016)
					(thickness 0.1524)
				)
			)
		)
		(duplicate_pad_numbers_are_jumpers no)
		(fp_line
			(start 1.651 1.778)
			(end 1.651 -1.778)
			(stroke
				(width 0.1524)
				(type default)
			)
			(layer "F.SilkS")
		)
		(fp_line
			(start 1.651 -1.778)
			(end -1.651 -1.778)
			(stroke
				(width 0.1524)
				(type default)
			)
			(layer "F.SilkS")
		)
		(fp_line
			(start -1.651 1.778)
			(end 1.651 1.778)
			(stroke
				(width 0.1524)
				(type default)
			)
			(layer "F.SilkS")
		)
		(fp_line
			(start -1.651 -1.778)
			(end -1.651 1.778)
			(stroke
				(width 0.1524)
				(type default)
			)
			(layer "F.SilkS")
		)
		(fp_poly
			(pts
				(xy -1.778 1.8796) (xy -1.778 -1.8796) (xy 1.778 -1.8796) (xy 1.778 1.8796)
			)
			(stroke
				(width 0)
				(type default)
			)
			(fill no)
			(layer "F.CrtYd")
		)
		(fp_poly
			(pts
				(xy -1.778 1.8796) (xy -1.778 -1.8796) (xy 1.778 -1.8796) (xy 1.778 1.8796)
			)
			(stroke
				(width 0)
				(type default)
			)
			(fill no)
			(layer "F.Fab")
		)
		(pad "D" smd custom
			(at 0 -0.9525 180)
			(size 0.1905 0.1905)
			(layers "F.Cu" "F.Mask" "F.Paste")
			(net "FLT_HDD11_N")
			(options
				(clearance outline)
				(anchor circle)
			)
			(primitives
				(gr_poly
					(pts
						(arc
							(start -0.1778 0.5715)
							(mid -0.321484 0.511984)
							(end -0.381 0.3683)
						)
						(arc
							(start -0.381 -0.3683)
							(mid -0.321484 -0.511984)
							(end -0.1778 -0.5715)
						)
						(arc
							(start 0.1778 -0.5715)
							(mid 0.321484 -0.511984)
							(end 0.381 -0.3683)
						)
						(arc
							(start 0.381 0.3683)
							(mid 0.321484 0.511984)
							(end 0.1778 0.5715)
						)
					)
					(width 0)
					(fill yes)
				)
			)
		)
		(pad "G" smd custom
			(at -0.98425 0.9525 180)
			(size 0.1905 0.1905)
			(layers "F.Cu" "F.Mask" "F.Paste")
			(net "DRIVE_B_11_FLT_LED")
			(options
				(clearance outline)
				(anchor circle)
			)
			(primitives
				(gr_poly
					(pts
						(arc
							(start -0.1778 0.5715)
							(mid -0.321484 0.511984)
							(end -0.381 0.3683)
						)
						(arc
							(start -0.381 -0.3683)
							(mid -0.321484 -0.511984)
							(end -0.1778 -0.5715)
						)
						(arc
							(start 0.1778 -0.5715)
							(mid 0.321484 -0.511984)
							(end 0.381 -0.3683)
						)
						(arc
							(start 0.381 0.3683)
							(mid 0.321484 0.511984)
							(end 0.1778 0.5715)
						)
					)
					(width 0)
					(fill yes)
				)
			)
		)
		(pad "S" smd custom
			(at 0.98425 0.9525 180)
			(size 0.1905 0.1905)
			(layers "F.Cu" "F.Mask" "F.Paste")
			(net "GND")
			(options
				(clearance outline)
				(anchor circle)
			)
			(primitives
				(gr_poly
					(pts
						(arc
							(start -0.1778 0.5715)
							(mid -0.321484 0.511984)
							(end -0.381 0.3683)
						)
						(arc
							(start -0.381 -0.3683)
							(mid -0.321484 -0.511984)
							(end -0.1778 -0.5715)
						)
						(arc
							(start 0.1778 -0.5715)
							(mid 0.321484 -0.511984)
							(end 0.381 -0.3683)
						)
						(arc
							(start 0.381 0.3683)
							(mid 0.321484 0.511984)
							(end 0.1778 0.5715)
						)
					)
					(width 0)
					(fill yes)
				)
			)
		)
	)
	(footprint ""
		(layer "F.Cu")
		(at 336.804 -263.017)
		(property "Reference" "Q24"
			(at 0 0 0)
			(layer "F.SilkS")
			(hide yes)
			(effects
				(font
					(size 1.27 1.27)
				)
			)
		)
		(property "Value" "AO4407AL-GP"
			(at -3.707384 -1.5367 0)
			(unlocked yes)
			(layer "F.Fab")
			(hide yes)
			(effects
				(font
					(size 1.016 1.016)
					(thickness 0.1524)
				)
			)
		)
		(property "Device Type" "SOIC8H69"
			(at -3.707384 -3.0607 0)
			(unlocked yes)
			(layer "F.Fab")
			(hide yes)
			(effects
				(font
					(size 1.016 1.016)
					(thickness 0.1524)
				)
			)
		)
		(duplicate_pad_numbers_are_jumpers no)
		(fp_line
			(start -2.7432 -1.4224)
			(end -2.7432 1.4224)
			(stroke
				(width 0.1524)
				(type default)
			)
			(layer "F.SilkS")
		)
		(fp_line
			(start -2.7432 1.4224)
			(end -2.6416 1.4224)
			(stroke
				(width 0.1524)
				(type default)
			)
			(layer "F.SilkS")
		)
		(fp_line
			(start -2.7432 1.4224)
			(end 2.1336 1.4224)
			(stroke
				(width 0.1524)
				(type default)
			)
			(layer "F.SilkS")
		)
		(fp_line
			(start -2.7178 -0.508)
			(end -2.1844 -0.0508)
			(stroke
				(width 0.1524)
				(type default)
			)
			(layer "F.SilkS")
		)
		(fp_line
			(start -2.6289 3.4417)
			(end -2.6289 1.4732)
			(stroke
				(width 0.381)
				(type default)
			)
			(layer "F.SilkS")
		)
		(fp_line
			(start -2.1844 -0.0508)
			(end -2.7178 0.508)
			(stroke
				(width 0.1524)
				(type default)
			)
			(layer "F.SilkS")
		)
		(fp_line
			(start 2.1336 -1.4224)
			(end -2.7432 -1.4224)
			(stroke
				(width 0.1524)
				(type default)
			)
			(layer "F.SilkS")
		)
		(fp_line
			(start 2.1336 1.4224)
			(end 2.1336 -1.4224)
			(stroke
				(width 0.1524)
				(type default)
			)
			(layer "F.SilkS")
		)
		(fp_poly
			(pts
				(xy -2.2098 -1.4224) (xy -2.2098 1.4224) (xy 2.2098 1.4224) (xy 2.2098 -1.4224)
			)
			(stroke
				(width 0)
				(type default)
			)
			(fill yes)
			(layer "F.SilkS")
		)
		(fp_rect
			(start -2.450084 2.999994)
			(end 2.450084 -2.999994)
			(stroke
				(width 0)
				(type default)
			)
			(fill no)
			(layer "F.CrtYd")
		)
		(fp_poly
			(pts
				(xy -2.8194 3.6322) (xy -2.8194 -3.6322) (xy 2.8194 -3.6322) (xy 2.8194 1.18364) (xy 2.450084 1.18364)
				(xy 2.450084 -2.999994) (xy -2.450084 -2.999994) (xy -2.450084 2.999994) (xy 2.450084 2.999994)
				(xy 2.450084 1.18618) (xy 2.8194 1.18618) (xy 2.8194 3.6322)
			)
			(stroke
				(width 0)
				(type default)
			)
			(fill no)
			(layer "F.CrtYd")
		)
		(fp_rect
			(start -2.8194 3.6322)
			(end 2.8194 -3.6322)
			(stroke
				(width 0)
				(type default)
			)
			(fill no)
			(layer "F.Fab")
		)
		(pad "1" smd rect
			(at -1.905 2.54)
			(size 0.635 1.651)
			(layers "F.Cu" "F.Mask" "F.Paste")
			(net "P12V_B")
		)
		(pad "2" smd rect
			(at -0.635 2.54)
			(size 0.635 1.651)
			(layers "F.Cu" "F.Mask" "F.Paste")
			(net "P12V_B")
		)
		(pad "3" smd rect
			(at 0.635 2.54)
			(size 0.635 1.651)
			(layers "F.Cu" "F.Mask" "F.Paste")
			(net "P12V_B")
		)
		(pad "4" smd rect
			(at 1.905 2.54)
			(size 0.635 1.651)
			(layers "F.Cu" "F.Mask" "F.Paste")
			(net "SW_HDD_N6")
		)
		(pad "5" smd rect
			(at 1.905 -2.54)
			(size 0.635 1.651)
			(layers "F.Cu" "F.Mask" "F.Paste")
			(net "P12V_HDD6")
		)
		(pad "6" smd rect
			(at 0.635 -2.54)
			(size 0.635 1.651)
			(layers "F.Cu" "F.Mask" "F.Paste")
			(net "P12V_HDD6")
		)
		(pad "7" smd rect
			(at -0.635 -2.54)
			(size 0.635 1.651)
			(layers "F.Cu" "F.Mask" "F.Paste")
			(net "P12V_HDD6")
		)
		(pad "8" smd rect
			(at -1.905 -2.54)
			(size 0.635 1.651)
			(layers "F.Cu" "F.Mask" "F.Paste")
			(net "P12V_HDD6")
		)
	)
	(footprint ""
		(layer "F.Cu")
		(at 211.95538 -247.88622)
		(property "Reference" "R42"
			(at 0 0 0)
			(layer "F.SilkS")
			(hide yes)
			(effects
				(font
					(size 1.27 1.27)
				)
			)
		)
		(property "Value" "4K7R2F-GP"
			(at 0.064008 -3.993896 0)
			(unlocked yes)
			(layer "F.Fab")
			(hide yes)
			(effects
				(font
					(size 1.016 1.016)
					(thickness 0.1524)
				)
			)
		)
		(property "Device Type" "R402H16"
			(at 0.064008 -5.517896 0)
			(unlocked yes)
			(layer "F.Fab")
			(hide yes)
			(effects
				(font
					(size 1.016 1.016)
					(thickness 0.1524)
				)
			)
		)
		(duplicate_pad_numbers_are_jumpers no)
		(fp_line
			(start -0.508 -0.9398)
			(end -0.508 0.9398)
			(stroke
				(width 0.1524)
				(type default)
			)
			(layer "F.SilkS")
		)
		(fp_line
			(start 0.508 -0.9398)
			(end -0.508 -0.9398)
			(stroke
				(width 0.1524)
				(type default)
			)
			(layer "F.SilkS")
		)
		(fp_rect
			(start -0.508 0.9398)
			(end 0.508 -0.9398)
			(stroke
				(width 0)
				(type default)
			)
			(fill no)
			(layer "F.CrtYd")
		)
		(fp_rect
			(start -0.508 0.9398)
			(end 0.508 -0.9398)
			(stroke
				(width 0)
				(type default)
			)
			(fill no)
			(layer "F.Fab")
		)
		(pad "1" smd custom
			(at 0 -0.4445)
			(size 0.1397 0.1397)
			(layers "F.Cu" "F.Mask" "F.Paste")
			(net "P3V3_STBY_B")
			(options
				(clearance outline)
				(anchor circle)
			)
			(primitives
				(gr_poly
					(pts
						(arc
							(start -0.1778 -0.2794)
							(mid -0.249642 -0.249642)
							(end -0.2794 -0.1778)
						)
						(arc
							(start -0.2794 0.1778)
							(mid -0.249642 0.249642)
							(end -0.1778 0.2794)
						)
						(arc
							(start 0.1778 0.2794)
							(mid 0.249642 0.249642)
							(end 0.2794 0.1778)
						)
						(arc
							(start 0.2794 -0.1778)
							(mid 0.249642 -0.249642)
							(end 0.1778 -0.2794)
						)
					)
					(width 0)
					(fill yes)
				)
			)
		)
		(pad "2" smd custom
			(at 0 0.4445)
			(size 0.1397 0.1397)
			(layers "F.Cu" "F.Mask" "F.Paste")
			(net "IO_EXP4_A1")
			(options
				(clearance outline)
				(anchor circle)
			)
			(primitives
				(gr_poly
					(pts
						(arc
							(start -0.1778 -0.2794)
							(mid -0.249642 -0.249642)
							(end -0.2794 -0.1778)
						)
						(arc
							(start -0.2794 0.1778)
							(mid -0.249642 0.249642)
							(end -0.1778 0.2794)
						)
						(arc
							(start 0.1778 0.2794)
							(mid 0.249642 0.249642)
							(end 0.2794 0.1778)
						)
						(arc
							(start 0.2794 -0.1778)
							(mid 0.249642 -0.249642)
							(end 0.1778 -0.2794)
						)
					)
					(width 0)
					(fill yes)
				)
			)
		)
	)
)
